(kicad_pcb
	(version 20260206)
	(generator "pcbnew")
	(generator_version "10.0")
	(general
		(thickness 1.6)
		(legacy_teardrops no)
	)
	(paper "A4")
	(title_block
		(title "04192023_DAF0TMB3IC0_F0TG_MB_C_brd_V02_OCP.brd")
		(comment 1 "Grand Teton / footprint 3955 of 8354 (U25), pads 2669-2779 of 6102")
	)
	(layers
		(0 "F.Cu" signal "TOP")
		(4 "In1.Cu" signal "GND")
		(6 "In2.Cu" signal "IN1")
		(8 "In3.Cu" signal "GND1")
		(10 "In4.Cu" signal "IN2")
		(12 "In5.Cu" signal "GND2")
		(14 "In6.Cu" signal "IN3")
		(16 "In7.Cu" signal "GND3")
		(18 "In8.Cu" signal "VCC")
		(20 "In9.Cu" signal "VCC1")
		(22 "In10.Cu" signal "GND4")
		(24 "In11.Cu" signal "IN4")
		(26 "In12.Cu" signal "GND5")
		(28 "In13.Cu" signal "IN5")
		(30 "In14.Cu" signal "GND6")
		(32 "In15.Cu" signal "IN6")
		(34 "In16.Cu" signal "GND7")
		(2 "B.Cu" signal "BOTTOM")
		(9 "F.Adhes" user "F.Adhesive")
		(11 "B.Adhes" user "B.Adhesive")
		(13 "F.Paste" user "Package Geometry/Pastemask Top")
		(15 "B.Paste" user "Package Geometry/Pastemask Bottom")
		(5 "F.SilkS" user "Ref Des/Silkscreen Top")
		(7 "B.SilkS" user "Ref Des/Silkscreen Bottom")
		(1 "F.Mask" user "Board Geometry/Soldermask Top")
		(3 "B.Mask" user "Board Geometry/Soldermask Bottom")
		(17 "Dwgs.User" user "User.Drawings")
		(19 "Cmts.User" user "User.Comments")
		(21 "Eco1.User" user "User.Eco1")
		(23 "Eco2.User" user "User.Eco2")
		(25 "Edge.Cuts" user "Board Geometry/Outline")
		(27 "Margin" user)
		(31 "F.CrtYd" user "Package Geometry/Place Bound Top")
		(29 "B.CrtYd" user "Package Geometry/Place Bound Bottom")
		(35 "F.Fab" user "Ref Des/Assembly Top")
		(33 "B.Fab" user "Ref Des/Assembly Bottom")
	)
	(footprint ""
		(layer "F.Cu")
		(at 359.867962 -258.880102 180)
		(property "Reference" "U25"
			(at -45.78477 -62.086744 0)
			(unlocked yes)
			(layer "F.SilkS")
			(effects
				(font
					(size 0.7874 0.5842)
					(thickness 0.1524)
				)
			)
		)
		(property "Value" ""
			(at 0 0 180)
			(layer "F.Fab")
			(effects
				(font
					(size 1.27 1.27)
				)
			)
		)
		(duplicate_pad_numbers_are_jumpers no)
		(pad "BY6" smd circle
			(at -30.230064 13.320014 180)
			(size 0.450088 0.450088)
			(layers "F.Cu" "F.Mask" "F.Paste")
			(net "M_K_CPU0_SB_CB<0>")
		)
		(pad "BY7" smd circle
			(at -29.29001 13.320014 180)
			(size 0.450088 0.450088)
			(layers "F.Cu" "F.Mask" "F.Paste")
			(net "M_K_CPU0_SB_DQS_DP<4>")
		)
		(pad "BY8" smd circle
			(at -28.349956 13.320014 180)
			(size 0.450088 0.450088)
			(layers "F.Cu" "F.Mask" "F.Paste")
			(net "GND")
		)
		(pad "BY9" smd circle
			(at -27.409902 13.320014 180)
			(size 0.450088 0.450088)
			(layers "F.Cu" "F.Mask" "F.Paste")
			(net "M_L_CPU0_SB_CB<0>")
		)
		(pad "BY10" smd circle
			(at -26.470102 13.320014 180)
			(size 0.450088 0.450088)
			(layers "F.Cu" "F.Mask" "F.Paste")
			(net "GND")
		)
		(pad "BY11" smd circle
			(at -25.530048 13.320014 180)
			(size 0.450088 0.450088)
			(layers "F.Cu" "F.Mask" "F.Paste")
			(net "M_L_CPU0_SB_DQS_DP<4>")
		)
		(pad "BY12" smd circle
			(at -24.589994 13.320014 180)
			(size 0.450088 0.450088)
			(layers "F.Cu" "F.Mask" "F.Paste")
			(net "GND")
		)
		(pad "BY13" smd circle
			(at -23.64994 13.320014 180)
			(size 0.450088 0.450088)
			(layers "F.Cu" "F.Mask" "F.Paste")
			(net "M_H_CPU0_SB_CB<0>")
		)
		(pad "BY14" smd circle
			(at -22.709886 13.320014 180)
			(size 0.450088 0.450088)
			(layers "F.Cu" "F.Mask" "F.Paste")
			(net "M_H_CPU0_SB_DQS_DP<4>")
		)
		(pad "BY15" smd circle
			(at -21.770086 13.320014 180)
			(size 0.450088 0.450088)
			(layers "F.Cu" "F.Mask" "F.Paste")
			(net "GND")
		)
		(pad "BY16" smd circle
			(at -20.830032 13.320014 180)
			(size 0.450088 0.450088)
			(layers "F.Cu" "F.Mask" "F.Paste")
			(net "M_J_CPU0_SB_CB<0>")
		)
		(pad "BY17" smd circle
			(at -19.889978 13.320014 180)
			(size 0.450088 0.450088)
			(layers "F.Cu" "F.Mask" "F.Paste")
			(net "GND")
		)
		(pad "BY18" smd circle
			(at -18.949924 13.320014 180)
			(size 0.450088 0.450088)
			(layers "F.Cu" "F.Mask" "F.Paste")
			(net "M_J_CPU0_SB_DQS_DP<4>")
		)
		(pad "BY19" smd circle
			(at -18.010124 13.320014 180)
			(size 0.450088 0.450088)
			(layers "F.Cu" "F.Mask" "F.Paste")
			(net "GND")
		)
		(pad "BY20" smd circle
			(at -17.07007 13.320014 180)
			(size 0.450088 0.450088)
			(layers "F.Cu" "F.Mask" "F.Paste")
			(net "M_I_CPU0_SB_CB<0>")
		)
		(pad "BY21" smd circle
			(at -16.130016 13.320014 180)
			(size 0.450088 0.450088)
			(layers "F.Cu" "F.Mask" "F.Paste")
			(net "M_I_CPU0_SB_DQS_DP<4>")
		)
		(pad "BY22" smd circle
			(at -15.189962 13.320014 180)
			(size 0.450088 0.450088)
			(layers "F.Cu" "F.Mask" "F.Paste")
			(net "GND")
		)
		(pad "BY23" smd circle
			(at -14.249908 13.320014 180)
			(size 0.450088 0.450088)
			(layers "F.Cu" "F.Mask" "F.Paste")
			(net "PVDDCR_CPU1_P0")
		)
		(pad "BY24" smd circle
			(at -13.310108 13.320014 180)
			(size 0.450088 0.450088)
			(layers "F.Cu" "F.Mask" "F.Paste")
			(net "PVDDCR_CPU1_P0")
		)
		(pad "BY25" smd circle
			(at -12.370054 13.320014 180)
			(size 0.450088 0.450088)
			(layers "F.Cu" "F.Mask" "F.Paste")
			(net "GND")
		)
		(pad "BY26" smd circle
			(at -11.43 13.320014 180)
			(size 0.450088 0.450088)
			(layers "F.Cu" "F.Mask" "F.Paste")
			(net "PVDDCR_CPU1_P0")
		)
		(pad "BY27" smd circle
			(at -10.489946 13.320014 180)
			(size 0.450088 0.450088)
			(layers "F.Cu" "F.Mask" "F.Paste")
			(net "PVDDCR_CPU1_P0")
		)
		(pad "BY28" smd circle
			(at -9.549892 13.320014 180)
			(size 0.450088 0.450088)
			(layers "F.Cu" "F.Mask" "F.Paste")
			(net "GND")
		)
		(pad "BY29" smd circle
			(at -8.610092 13.320014 180)
			(size 0.450088 0.450088)
			(layers "F.Cu" "F.Mask" "F.Paste")
			(net "PVDDCR_CPU1_P0")
		)
		(pad "BY30" smd circle
			(at -7.670038 13.320014 180)
			(size 0.450088 0.450088)
			(layers "F.Cu" "F.Mask" "F.Paste")
			(net "PVDDCR_CPU1_P0")
		)
		(pad "BY31" smd circle
			(at -6.729984 13.320014 180)
			(size 0.450088 0.450088)
			(layers "F.Cu" "F.Mask" "F.Paste")
			(net "GND")
		)
		(pad "BY32" smd circle
			(at -5.78993 13.320014 180)
			(size 0.450088 0.450088)
			(layers "F.Cu" "F.Mask" "F.Paste")
			(net "PVDDCR_CPU1_P0")
		)
		(pad "BY33" smd circle
			(at -4.849876 13.320014 180)
			(size 0.450088 0.450088)
			(layers "F.Cu" "F.Mask" "F.Paste")
			(net "PVDDCR_CPU1_P0")
		)
		(pad "BY34" smd circle
			(at -3.910076 13.320014 180)
			(size 0.450088 0.450088)
			(layers "F.Cu" "F.Mask" "F.Paste")
			(net "GND")
		)
		(pad "BY35" smd circle
			(at -2.970022 13.320014 180)
			(size 0.450088 0.450088)
			(layers "F.Cu" "F.Mask" "F.Paste")
			(net "P5E_CPU0_P2_TX_DN<3>")
		)
		(pad "BY36" smd circle
			(at -2.029968 13.320014 180)
			(size 0.450088 0.450088)
			(layers "F.Cu" "F.Mask" "F.Paste")
			(net "P5E_CPU0_P2_TX_DP<3>")
		)
		(pad "BY37" smd circle
			(at -1.089914 13.320014 180)
			(size 0.450088 0.450088)
			(layers "F.Cu" "F.Mask" "F.Paste")
			(net "GND")
		)
		(pad "BY39" smd circle
			(at 0.78994 13.320014 180)
			(size 0.450088 0.450088)
			(layers "F.Cu" "F.Mask" "F.Paste")
			(net "GND")
		)
		(pad "BY40" smd circle
			(at 1.729994 13.320014 180)
			(size 0.450088 0.450088)
			(layers "F.Cu" "F.Mask" "F.Paste")
			(net "P5E_CPU0_P0_RX_DP<12>")
		)
		(pad "BY41" smd circle
			(at 2.670048 13.320014 180)
			(size 0.450088 0.450088)
			(layers "F.Cu" "F.Mask" "F.Paste")
			(net "P5E_CPU0_P0_RX_DN<12>")
		)
		(pad "BY42" smd circle
			(at 3.610102 13.320014 180)
			(size 0.450088 0.450088)
			(layers "F.Cu" "F.Mask" "F.Paste")
			(net "GND")
		)
		(pad "BY43" smd circle
			(at 4.549902 13.320014 180)
			(size 0.450088 0.450088)
			(layers "F.Cu" "F.Mask" "F.Paste")
			(net "PVDDCR_CPU1_P0")
		)
		(pad "BY44" smd circle
			(at 5.489956 13.320014 180)
			(size 0.450088 0.450088)
			(layers "F.Cu" "F.Mask" "F.Paste")
			(net "PVDDCR_CPU1_P0")
		)
		(pad "BY45" smd circle
			(at 6.43001 13.320014 180)
			(size 0.450088 0.450088)
			(layers "F.Cu" "F.Mask" "F.Paste")
			(net "GND")
		)
		(pad "BY46" smd circle
			(at 7.370064 13.320014 180)
			(size 0.450088 0.450088)
			(layers "F.Cu" "F.Mask" "F.Paste")
			(net "PVDDCR_CPU1_P0")
		)
		(pad "BY47" smd circle
			(at 8.310118 13.320014 180)
			(size 0.450088 0.450088)
			(layers "F.Cu" "F.Mask" "F.Paste")
			(net "PVDDCR_CPU1_P0")
		)
		(pad "BY48" smd circle
			(at 9.249918 13.320014 180)
			(size 0.450088 0.450088)
			(layers "F.Cu" "F.Mask" "F.Paste")
			(net "GND")
		)
		(pad "BY49" smd circle
			(at 10.189972 13.320014 180)
			(size 0.450088 0.450088)
			(layers "F.Cu" "F.Mask" "F.Paste")
			(net "PVDDCR_CPU1_P0")
		)
		(pad "BY50" smd circle
			(at 11.130026 13.320014 180)
			(size 0.450088 0.450088)
			(layers "F.Cu" "F.Mask" "F.Paste")
			(net "PVDDCR_CPU1_P0")
		)
		(pad "BY51" smd circle
			(at 12.07008 13.320014 180)
			(size 0.450088 0.450088)
			(layers "F.Cu" "F.Mask" "F.Paste")
			(net "GND")
		)
		(pad "BY52" smd circle
			(at 13.00988 13.320014 180)
			(size 0.450088 0.450088)
			(layers "F.Cu" "F.Mask" "F.Paste")
			(net "PVDDCR_CPU1_P0")
		)
		(pad "BY53" smd circle
			(at 13.949934 13.320014 180)
			(size 0.450088 0.450088)
			(layers "F.Cu" "F.Mask" "F.Paste")
			(net "PVDDCR_CPU1_P0")
		)
		(pad "BY54" smd circle
			(at 14.889988 13.320014 180)
			(size 0.450088 0.450088)
			(layers "F.Cu" "F.Mask" "F.Paste")
			(net "GND")
		)
		(pad "BY55" smd circle
			(at 15.830042 13.320014 180)
			(size 0.450088 0.450088)
			(layers "F.Cu" "F.Mask" "F.Paste")
			(net "M_C_CPU0_SB_DQS_DP<4>")
		)
		(pad "BY56" smd circle
			(at 16.770096 13.320014 180)
			(size 0.450088 0.450088)
			(layers "F.Cu" "F.Mask" "F.Paste")
			(net "M_C_CPU0_SB_CB<0>")
		)
		(pad "BY57" smd circle
			(at 17.709896 13.320014 180)
			(size 0.450088 0.450088)
			(layers "F.Cu" "F.Mask" "F.Paste")
			(net "GND")
		)
		(pad "BY58" smd circle
			(at 18.64995 13.320014 180)
			(size 0.450088 0.450088)
			(layers "F.Cu" "F.Mask" "F.Paste")
			(net "M_D_CPU0_SB_DQS_DP<4>")
		)
		(pad "BY59" smd circle
			(at 19.590004 13.320014 180)
			(size 0.450088 0.450088)
			(layers "F.Cu" "F.Mask" "F.Paste")
			(net "GND")
		)
		(pad "BY60" smd circle
			(at 20.530058 13.320014 180)
			(size 0.450088 0.450088)
			(layers "F.Cu" "F.Mask" "F.Paste")
			(net "M_D_CPU0_SB_CB<0>")
		)
		(pad "BY61" smd circle
			(at 21.470112 13.320014 180)
			(size 0.450088 0.450088)
			(layers "F.Cu" "F.Mask" "F.Paste")
			(net "GND")
		)
		(pad "BY62" smd circle
			(at 22.409912 13.320014 180)
			(size 0.450088 0.450088)
			(layers "F.Cu" "F.Mask" "F.Paste")
			(net "M_B_CPU0_SB_DQS_DP<4>")
		)
		(pad "BY63" smd circle
			(at 23.349966 13.320014 180)
			(size 0.450088 0.450088)
			(layers "F.Cu" "F.Mask" "F.Paste")
			(net "M_B_CPU0_SB_CB<0>")
		)
		(pad "BY64" smd circle
			(at 24.29002 13.320014 180)
			(size 0.450088 0.450088)
			(layers "F.Cu" "F.Mask" "F.Paste")
			(net "GND")
		)
		(pad "BY65" smd circle
			(at 25.230074 13.320014 180)
			(size 0.450088 0.450088)
			(layers "F.Cu" "F.Mask" "F.Paste")
			(net "M_F_CPU0_SB_DQS_DP<4>")
		)
		(pad "BY66" smd circle
			(at 26.170128 13.320014 180)
			(size 0.450088 0.450088)
			(layers "F.Cu" "F.Mask" "F.Paste")
			(net "GND")
		)
		(pad "BY67" smd circle
			(at 27.109928 13.320014 180)
			(size 0.450088 0.450088)
			(layers "F.Cu" "F.Mask" "F.Paste")
			(net "M_F_CPU0_SB_CB<0>")
		)
		(pad "BY68" smd circle
			(at 28.049982 13.320014 180)
			(size 0.450088 0.450088)
			(layers "F.Cu" "F.Mask" "F.Paste")
			(net "GND")
		)
		(pad "BY69" smd circle
			(at 28.990036 13.320014 180)
			(size 0.450088 0.450088)
			(layers "F.Cu" "F.Mask" "F.Paste")
			(net "M_E_CPU0_SB_DQS_DP<4>")
		)
		(pad "BY70" smd circle
			(at 29.93009 13.320014 180)
			(size 0.450088 0.450088)
			(layers "F.Cu" "F.Mask" "F.Paste")
			(net "M_E_CPU0_SB_CB<0>")
		)
		(pad "BY71" smd circle
			(at 30.86989 13.320014 180)
			(size 0.450088 0.450088)
			(layers "F.Cu" "F.Mask" "F.Paste")
			(net "GND")
		)
		(pad "BY72" smd circle
			(at 31.809944 13.320014 180)
			(size 0.450088 0.450088)
			(layers "F.Cu" "F.Mask" "F.Paste")
			(net "M_A_CPU0_SB_DQS_DP<4>")
		)
		(pad "BY73" smd circle
			(at 32.749998 13.320014 180)
			(size 0.450088 0.450088)
			(layers "F.Cu" "F.Mask" "F.Paste")
			(net "GND")
		)
		(pad "BY74" smd circle
			(at 33.690052 13.320014 180)
			(size 0.450088 0.450088)
			(layers "F.Cu" "F.Mask" "F.Paste")
			(net "M_A_CPU0_SB_CB<0>")
		)
		(pad "C1" smd circle
			(at -34.159952 -35.189922 180)
			(size 0.450088 0.450088)
			(layers "F.Cu" "F.Mask" "F.Paste")
			(net "GND")
		)
		(pad "C2" smd circle
			(at -33.219898 -35.189922 180)
			(size 0.450088 0.450088)
			(layers "F.Cu" "F.Mask" "F.Paste")
			(net "VSENSE_PVDDCR_CPU0_P0_DP")
		)
		(pad "C3" smd circle
			(at -32.280098 -35.189922 180)
			(size 0.450088 0.450088)
			(layers "F.Cu" "F.Mask" "F.Paste")
			(net "VSENSE_VSS_SENSE_A_P0")
		)
		(pad "C4" smd circle
			(at -31.340044 -35.189922 180)
			(size 0.450088 0.450088)
			(layers "F.Cu" "F.Mask" "F.Paste")
			(net "PVDDCR_SOC_P0")
		)
		(pad "C5" smd circle
			(at -30.39999 -35.189922 180)
			(size 0.450088 0.450088)
			(layers "F.Cu" "F.Mask" "F.Paste")
			(net "GND")
		)
		(pad "C6" smd circle
			(at -29.459936 -35.189922 180)
			(size 0.450088 0.450088)
			(layers "F.Cu" "F.Mask" "F.Paste")
			(net "CLK_100M_CPU0_CLK02_R_DN")
		)
		(pad "C7" smd circle
			(at -28.519882 -35.189922 180)
			(size 0.450088 0.450088)
			(layers "F.Cu" "F.Mask" "F.Paste")
			(net "I3C_1_SPD_DDRGL_CPU0_R_SCL")
		)
		(pad "C8" smd circle
			(at -27.580082 -35.189922 180)
			(size 0.450088 0.450088)
			(layers "F.Cu" "F.Mask" "F.Paste")
			(net "GND")
		)
		(pad "C9" smd circle
			(at -26.640028 -35.189922 180)
			(size 0.450088 0.450088)
			(layers "F.Cu" "F.Mask" "F.Paste")
			(net "CLK_100M_CPU0_CLK05_R_DN")
		)
		(pad "C10" smd circle
			(at -25.699974 -35.189922 180)
			(size 0.450088 0.450088)
			(layers "F.Cu" "F.Mask" "F.Paste")
			(net "GND")
		)
		(pad "C11" smd circle
			(at -24.75992 -35.189922 180)
			(size 0.450088 0.450088)
			(layers "F.Cu" "F.Mask" "F.Paste")
			(net "GND")
		)
		(pad "C12" smd circle
			(at -23.82012 -35.189922 180)
			(size 0.450088 0.450088)
			(layers "F.Cu" "F.Mask" "F.Paste")
			(net "CLK_100M_CPU0_CLK04_R_DN")
		)
		(pad "C13" smd circle
			(at -22.880066 -35.189922 180)
			(size 0.450088 0.450088)
			(layers "F.Cu" "F.Mask" "F.Paste")
			(net "GND")
		)
		(pad "C14" smd circle
			(at -21.940012 -35.189922 180)
			(size 0.450088 0.450088)
			(layers "F.Cu" "F.Mask" "F.Paste")
			(net "FAB_REV_ID1")
		)
		(pad "C15" smd circle
			(at -20.999958 -35.189922 180)
			(size 0.450088 0.450088)
			(layers "F.Cu" "F.Mask" "F.Paste")
			(net "GND")
		)
		(pad "C16" smd circle
			(at -20.059904 -35.189922 180)
			(size 0.450088 0.450088)
			(layers "F.Cu" "F.Mask" "F.Paste")
			(net "JTAG_CPU0_DBREQ_N")
		)
		(pad "C17" smd circle
			(at -19.120104 -35.189922 180)
			(size 0.450088 0.450088)
			(layers "F.Cu" "F.Mask" "F.Paste")
			(net "JTAG_CPU0_TDI")
		)
		(pad "C18" smd circle
			(at -18.18005 -35.189922 180)
			(size 0.450088 0.450088)
			(layers "F.Cu" "F.Mask" "F.Paste")
			(net "JTAG_CPU0_R_TDO")
		)
		(pad "C19" smd circle
			(at -17.239996 -35.189922 180)
			(size 0.450088 0.450088)
			(layers "F.Cu" "F.Mask" "F.Paste")
			(net "CPU0_SP5R1")
		)
		(pad "C20" smd circle
			(at -16.299942 -35.189922 180)
			(size 0.450088 0.450088)
			(layers "F.Cu" "F.Mask" "F.Paste")
			(net "PVDDCR_CPU0_P0")
		)
		(pad "C21" smd circle
			(at -15.359888 -35.189922 180)
			(size 0.450088 0.450088)
			(layers "F.Cu" "F.Mask" "F.Paste")
			(net "GND")
		)
		(pad "C22" smd circle
			(at -14.420088 -35.189922 180)
			(size 0.450088 0.450088)
			(layers "F.Cu" "F.Mask" "F.Paste")
			(net "FM_P0_PCC0_N")
		)
		(pad "C23" smd circle
			(at -13.480034 -35.189922 180)
			(size 0.450088 0.450088)
			(layers "F.Cu" "F.Mask" "F.Paste")
			(net "Net_1949")
		)
		(pad "C24" smd circle
			(at -12.53998 -35.189922 180)
			(size 0.450088 0.450088)
			(layers "F.Cu" "F.Mask" "F.Paste")
			(net "GND")
		)
		(pad "C25" smd circle
			(at -11.599926 -35.189922 180)
			(size 0.450088 0.450088)
			(layers "F.Cu" "F.Mask" "F.Paste")
			(net "USB3_CPU0_BMC_TX_DP")
		)
		(pad "C26" smd circle
			(at -10.659872 -35.189922 180)
			(size 0.450088 0.450088)
			(layers "F.Cu" "F.Mask" "F.Paste")
			(net "USB3_CPU0_BMC_TX_DN")
		)
		(pad "C27" smd circle
			(at -9.720072 -35.189922 180)
			(size 0.450088 0.450088)
			(layers "F.Cu" "F.Mask" "F.Paste")
			(net "GND")
		)
		(pad "C28" smd circle
			(at -8.780018 -35.189922 180)
			(size 0.450088 0.450088)
			(layers "F.Cu" "F.Mask" "F.Paste")
			(net "Net_1884")
		)
		(pad "C29" smd circle
			(at -7.839964 -35.189922 180)
			(size 0.450088 0.450088)
			(layers "F.Cu" "F.Mask" "F.Paste")
			(net "Net_1885")
		)
		(pad "C30" smd circle
			(at -6.89991 -35.189922 180)
			(size 0.450088 0.450088)
			(layers "F.Cu" "F.Mask" "F.Paste")
			(net "GND")
		)
		(pad "C31" smd circle
			(at -5.96011 -35.189922 180)
			(size 0.450088 0.450088)
			(layers "F.Cu" "F.Mask" "F.Paste")
			(net "Net_1925")
		)
		(pad "C32" smd circle
			(at -5.020056 -35.189922 180)
			(size 0.450088 0.450088)
			(layers "F.Cu" "F.Mask" "F.Paste")
			(net "NC_CPU0_AZ_BITCLK")
		)
		(pad "C33" smd circle
			(at -4.080002 -35.189922 180)
			(size 0.450088 0.450088)
			(layers "F.Cu" "F.Mask" "F.Paste")
			(net "NC_CPU0_AZ_SDIN0")
		)
		(pad "C34" smd circle
			(at -3.139948 -35.189922 180)
			(size 0.450088 0.450088)
			(layers "F.Cu" "F.Mask" "F.Paste")
			(net "Net_1926")
		)
		(pad "C35" smd circle
			(at -2.199894 -35.189922 180)
			(size 0.450088 0.450088)
			(layers "F.Cu" "F.Mask" "F.Paste")
			(net "Net_1927")
		)
		(pad "C36" smd circle
			(at -1.260094 -35.189922 180)
			(size 0.450088 0.450088)
			(layers "F.Cu" "F.Mask" "F.Paste")
			(net "GND")
		)
		(pad "C40" smd circle
			(at 1.560068 -35.189922 180)
			(size 0.450088 0.450088)
			(layers "F.Cu" "F.Mask" "F.Paste")
			(net "GND")
		)
		(pad "C41" smd circle
			(at 2.500122 -35.189922 180)
			(size 0.450088 0.450088)
			(layers "F.Cu" "F.Mask" "F.Paste")
			(net "Net_1870")
		)
		(pad "C42" smd circle
			(at 3.439922 -35.189922 180)
			(size 0.450088 0.450088)
			(layers "F.Cu" "F.Mask" "F.Paste")
			(net "Net_1869")
		)
		(pad "C43" smd circle
			(at 4.379976 -35.189922 180)
			(size 0.450088 0.450088)
			(layers "F.Cu" "F.Mask" "F.Paste")
			(net "GND")
		)
		(pad "C44" smd circle
			(at 5.32003 -35.189922 180)
			(size 0.450088 0.450088)
			(layers "F.Cu" "F.Mask" "F.Paste")
			(net "P2E_CPU0_P5_TX_DP")
		)
		(pad "C45" smd circle
			(at 6.260084 -35.189922 180)
			(size 0.450088 0.450088)
			(layers "F.Cu" "F.Mask" "F.Paste")
			(net "P2E_CPU0_P5_TX_DN")
		)
		(pad "C46" smd circle
			(at 7.199884 -35.189922 180)
			(size 0.450088 0.450088)
			(layers "F.Cu" "F.Mask" "F.Paste")
			(net "GND")
		)
	)
)
